# S9S_MB_2U (Grand Teton) — schematic netlist excerpt (pin names and nets, part order shuffled) for the footprints in the layout excerpt that follows; sources: Cadence DE-HDL packaged netlist, KiCad conversion of 03242023_DA0F0TMBIJ0_F0T_Motherboard_J_brd_V01_OCP.brd

R1785  Q_RES  4.7K 1% CHIP  pkg 0402LF  page 250 : A = P3V3_AUX_ADC ; B = GND
R776  Q_RES  100 1% CHIP  pkg 0402LF  page 131 : A = JTAG_DBP_TDO_R ; B = JTAG_DBP_TDO

(kicad_pcb
	(version 20260206)
	(generator "pcbnew")
	(generator_version "10.0")
	(general
		(thickness 1.6)
		(legacy_teardrops no)
	)
	(paper "A4")
	(title_block
		(title "03242023_DA0F0TMBIJ0_F0T_Motherboard_J_brd_V01_OCP.brd")
		(comment 1 "Grand Teton / footprints 333-334 of 6105")
	)
	(layers
		(0 "F.Cu" signal "TOP")
		(4 "In1.Cu" signal "GND")
		(6 "In2.Cu" signal "IN1")
		(8 "In3.Cu" signal "GND1")
		(10 "In4.Cu" signal "IN2")
		(12 "In5.Cu" signal "GND2")
		(14 "In6.Cu" signal "IN3")
		(16 "In7.Cu" signal "GND3")
		(18 "In8.Cu" signal "VCC")
		(20 "In9.Cu" signal "VCC1")
		(22 "In10.Cu" signal "GND4")
		(24 "In11.Cu" signal "IN4")
		(26 "In12.Cu" signal "GND5")
		(28 "In13.Cu" signal "IN5")
		(30 "In14.Cu" signal "GND6")
		(32 "In15.Cu" signal "IN6")
		(34 "In16.Cu" signal "GND7")
		(2 "B.Cu" signal "BOTTOM")
		(9 "F.Adhes" user "F.Adhesive")
		(11 "B.Adhes" user "B.Adhesive")
		(13 "F.Paste" user "Package Geometry/Pastemask Top")
		(15 "B.Paste" user "Package Geometry/Pastemask Bottom")
		(5 "F.SilkS" user "Ref Des/Silkscreen Top")
		(7 "B.SilkS" user "Ref Des/Silkscreen Bottom")
		(1 "F.Mask" user "Board Geometry/Soldermask Top")
		(3 "B.Mask" user "Board Geometry/Soldermask Bottom")
		(17 "Dwgs.User" user "User.Drawings")
		(19 "Cmts.User" user "User.Comments")
		(21 "Eco1.User" user "User.Eco1")
		(23 "Eco2.User" user "User.Eco2")
		(25 "Edge.Cuts" user "Board Geometry/Outline")
		(27 "Margin" user)
		(31 "F.CrtYd" user "Package Geometry/Place Bound Top")
		(29 "B.CrtYd" user "Package Geometry/Place Bound Bottom")
		(35 "F.Fab" user "Ref Des/Assembly Top")
		(33 "B.Fab" user "Ref Des/Assembly Bottom")
	)
	(footprint ""
		(layer "F.Cu")
		(at 385.734052 -68.126356 180)
		(property "Reference" "R776"
			(at 0 0 180)
			(layer "F.SilkS")
			(hide yes)
			(effects
				(font
					(size 1.27 1.27)
				)
			)
		)
		(property "Value" ""
			(at 0 0 180)
			(layer "F.Fab")
			(effects
				(font
					(size 1.27 1.27)
				)
			)
		)
		(duplicate_pad_numbers_are_jumpers no)
		(fp_line
			(start 0.7874 0.4064)
			(end -0.7874 0.4064)
			(stroke
				(width 0.1524)
				(type default)
			)
			(layer "F.SilkS")
		)
		(fp_line
			(start 0.7874 -0.4064)
			(end 0.7874 0.4064)
			(stroke
				(width 0.1524)
				(type default)
			)
			(layer "F.SilkS")
		)
		(fp_line
			(start -0.7874 0.4064)
			(end -0.7874 -0.4064)
			(stroke
				(width 0.1524)
				(type default)
			)
			(layer "F.SilkS")
		)
		(fp_line
			(start -0.7874 -0.4064)
			(end 0.7874 -0.4064)
			(stroke
				(width 0.1524)
				(type default)
			)
			(layer "F.SilkS")
		)
		(fp_line
			(start 0.67945 0.3048)
			(end 0.120396 0.3048)
			(stroke
				(width 0.1)
				(type default)
			)
			(layer "F.Fab")
		)
		(fp_line
			(start 0.67945 -0.3048)
			(end 0.67945 0.3048)
			(stroke
				(width 0.1)
				(type default)
			)
			(layer "F.Fab")
		)
		(fp_line
			(start 0.12065 -0.2794)
			(end 0.12065 -0.3048)
			(stroke
				(width 0.1)
				(type default)
			)
			(layer "F.Fab")
		)
		(fp_line
			(start 0.12065 -0.3048)
			(end 0.67945 -0.3048)
			(stroke
				(width 0.1)
				(type default)
			)
			(layer "F.Fab")
		)
		(fp_line
			(start 0.120396 0.3048)
			(end 0.120396 0.2794)
			(stroke
				(width 0.1)
				(type default)
			)
			(layer "F.Fab")
		)
		(fp_line
			(start 0.120396 0.2794)
			(end -0.12065 0.2794)
			(stroke
				(width 0.1)
				(type default)
			)
			(layer "F.Fab")
		)
		(fp_line
			(start -0.12065 0.3048)
			(end -0.67945 0.3048)
			(stroke
				(width 0.1)
				(type default)
			)
			(layer "F.Fab")
		)
		(fp_line
			(start -0.12065 0.2794)
			(end -0.12065 0.3048)
			(stroke
				(width 0.1)
				(type default)
			)
			(layer "F.Fab")
		)
		(fp_line
			(start -0.12065 -0.2794)
			(end 0.12065 -0.2794)
			(stroke
				(width 0.1)
				(type default)
			)
			(layer "F.Fab")
		)
		(fp_line
			(start -0.12065 -0.305054)
			(end -0.12065 -0.2794)
			(stroke
				(width 0.1)
				(type default)
			)
			(layer "F.Fab")
		)
		(fp_line
			(start -0.67945 0.3048)
			(end -0.67945 -0.305054)
			(stroke
				(width 0.1)
				(type default)
			)
			(layer "F.Fab")
		)
		(fp_line
			(start -0.67945 -0.305054)
			(end -0.12065 -0.305054)
			(stroke
				(width 0.1)
				(type default)
			)
			(layer "F.Fab")
		)
		(pad "1" smd circle
			(at -0.40005 0 180)
			(size 0 0)
			(layers "F.Cu" "F.Mask" "F.Paste")
			(net "JTAG_DBP_TDO_R")
		)
		(pad "2" smd circle
			(at 0.40005 0 180)
			(size 0 0)
			(layers "F.Cu" "F.Mask" "F.Paste")
			(net "JTAG_DBP_TDO")
		)
	)
	(footprint ""
		(layer "F.Cu")
		(at 44.169584 -107.031282)
		(property "Reference" "R1785"
			(at 0 0 0)
			(layer "F.SilkS")
			(hide yes)
			(effects
				(font
					(size 1.27 1.27)
				)
			)
		)
		(property "Value" ""
			(at 0 0 0)
			(layer "F.Fab")
			(effects
				(font
					(size 1.27 1.27)
				)
			)
		)
		(duplicate_pad_numbers_are_jumpers no)
		(fp_line
			(start -0.7874 -0.4064)
			(end 0.7874 -0.4064)
			(stroke
				(width 0.1524)
				(type default)
			)
			(layer "F.SilkS")
		)
		(fp_line
			(start -0.7874 0.4064)
			(end -0.7874 -0.4064)
			(stroke
				(width 0.1524)
				(type default)
			)
			(layer "F.SilkS")
		)
		(fp_line
			(start 0.7874 -0.4064)
			(end 0.7874 0.4064)
			(stroke
				(width 0.1524)
				(type default)
			)
			(layer "F.SilkS")
		)
		(fp_line
			(start 0.7874 0.4064)
			(end -0.7874 0.4064)
			(stroke
				(width 0.1524)
				(type default)
			)
			(layer "F.SilkS")
		)
		(fp_line
			(start -0.67945 -0.305054)
			(end -0.12065 -0.305054)
			(stroke
				(width 0.1)
				(type default)
			)
			(layer "F.Fab")
		)
		(fp_line
			(start -0.67945 0.3048)
			(end -0.67945 -0.305054)
			(stroke
				(width 0.1)
				(type default)
			)
			(layer "F.Fab")
		)
		(fp_line
			(start -0.12065 -0.305054)
			(end -0.12065 -0.2794)
			(stroke
				(width 0.1)
				(type default)
			)
			(layer "F.Fab")
		)
		(fp_line
			(start -0.12065 -0.2794)
			(end 0.12065 -0.2794)
			(stroke
				(width 0.1)
				(type default)
			)
			(layer "F.Fab")
		)
		(fp_line
			(start -0.12065 0.2794)
			(end -0.12065 0.3048)
			(stroke
				(width 0.1)
				(type default)
			)
			(layer "F.Fab")
		)
		(fp_line
			(start -0.12065 0.3048)
			(end -0.67945 0.3048)
			(stroke
				(width 0.1)
				(type default)
			)
			(layer "F.Fab")
		)
		(fp_line
			(start 0.120396 0.2794)
			(end -0.12065 0.2794)
			(stroke
				(width 0.1)
				(type default)
			)
			(layer "F.Fab")
		)
		(fp_line
			(start 0.120396 0.3048)
			(end 0.120396 0.2794)
			(stroke
				(width 0.1)
				(type default)
			)
			(layer "F.Fab")
		)
		(fp_line
			(start 0.12065 -0.3048)
			(end 0.67945 -0.3048)
			(stroke
				(width 0.1)
				(type default)
			)
			(layer "F.Fab")
		)
		(fp_line
			(start 0.12065 -0.2794)
			(end 0.12065 -0.3048)
			(stroke
				(width 0.1)
				(type default)
			)
			(layer "F.Fab")
		)
		(fp_line
			(start 0.67945 -0.3048)
			(end 0.67945 0.3048)
			(stroke
				(width 0.1)
				(type default)
			)
			(layer "F.Fab")
		)
		(fp_line
			(start 0.67945 0.3048)
			(end 0.120396 0.3048)
			(stroke
				(width 0.1)
				(type default)
			)
			(layer "F.Fab")
		)
		(pad "1" smd circle
			(at -0.40005 0)
			(size 0 0)
			(layers "F.Cu" "F.Mask" "F.Paste")
			(net "P3V3_AUX_ADC")
		)
		(pad "2" smd circle
			(at 0.40005 0)
			(size 0 0)
			(layers "F.Cu" "F.Mask" "F.Paste")
			(net "GND")
		)
	)
)
